(kicad_pcb
	(version 20260206)
	(generator "pcbnew")
	(generator_version "10.0")
	(general
		(thickness 1.6)
		(legacy_teardrops no)
	)
	(paper "A4")
	(title_block
		(title "Bryce Canyon_R.DPB_16317-1_OCP.brd")
		(comment 1 "Bryce Canyon / footprints 1408-1414 of 2099")
	)
	(layers
		(0 "F.Cu" signal "TOP")
		(4 "In1.Cu" signal "L2GND")
		(6 "In2.Cu" signal "L3")
		(8 "In3.Cu" signal "L4VCC")
		(10 "In4.Cu" signal "L5VCC")
		(12 "In5.Cu" signal "L6")
		(14 "In6.Cu" signal "L7GND")
		(2 "B.Cu" signal "BOTTOM")
		(9 "F.Adhes" user "F.Adhesive")
		(11 "B.Adhes" user "B.Adhesive")
		(13 "F.Paste" user "Package Geometry/Pastemask Top")
		(15 "B.Paste" user "Package Geometry/Pastemask Bottom")
		(5 "F.SilkS" user "Ref Des/Silkscreen Top")
		(7 "B.SilkS" user "Ref Des/Silkscreen Bottom")
		(1 "F.Mask" user "Board Geometry/Soldermask Top")
		(3 "B.Mask" user "Board Geometry/Soldermask Bottom")
		(17 "Dwgs.User" user "User.Drawings")
		(19 "Cmts.User" user "User.Comments")
		(21 "Eco1.User" user "User.Eco1")
		(23 "Eco2.User" user "User.Eco2")
		(25 "Edge.Cuts" user "Board Geometry/Outline")
		(27 "Margin" user)
		(31 "F.CrtYd" user "Package Geometry/Place Bound Top")
		(29 "B.CrtYd" user "Package Geometry/Place Bound Bottom")
		(35 "F.Fab" user "Ref Des/Assembly Top")
		(33 "B.Fab" user "Ref Des/Assembly Bottom")
	)
	(footprint ""
		(layer "F.Cu")
		(at 245.4402 -303.149 90)
		(property "Reference" "C616"
			(at 0 0 90)
			(layer "F.SilkS")
			(hide yes)
			(effects
				(font
					(size 1.27 1.27)
				)
			)
		)
		(property "Value" "SCD1U16V2KX-3GP"
			(at 1.1811 -2.7051 90)
			(unlocked yes)
			(layer "F.Fab")
			(hide yes)
			(effects
				(font
					(size 1.016 1.016)
					(thickness 0.1524)
				)
			)
		)
		(property "Device Type" "C402H22"
			(at 1.1811 -4.2291 90)
			(unlocked yes)
			(layer "F.Fab")
			(hide yes)
			(effects
				(font
					(size 1.016 1.016)
					(thickness 0.1524)
				)
			)
		)
		(duplicate_pad_numbers_are_jumpers no)
		(fp_rect
			(start -0.4318 0.9525)
			(end 0.4318 -0.9525)
			(stroke
				(width 0)
				(type default)
			)
			(fill no)
			(layer "F.CrtYd")
		)
		(fp_rect
			(start -0.4318 0.9525)
			(end 0.4318 -0.9525)
			(stroke
				(width 0)
				(type default)
			)
			(fill no)
			(layer "F.Fab")
		)
		(pad "1" smd custom
			(at 0 -0.4445 90)
			(size 0.1524 0.1524)
			(layers "F.Cu" "F.Mask" "F.Paste")
			(net "P3V3_STBY_A")
			(options
				(clearance outline)
				(anchor circle)
			)
			(primitives
				(gr_poly
					(pts
						(arc
							(start 0.3048 -0.2032)
							(mid 0.275042 -0.275042)
							(end 0.2032 -0.3048)
						)
						(arc
							(start -0.2032 -0.3048)
							(mid -0.275042 -0.275042)
							(end -0.3048 -0.2032)
						)
						(arc
							(start -0.3048 0.2032)
							(mid -0.275042 0.275042)
							(end -0.2032 0.3048)
						)
						(arc
							(start 0.2032 0.3048)
							(mid 0.275042 0.275042)
							(end 0.3048 0.2032)
						)
					)
					(width 0)
					(fill yes)
				)
			)
		)
		(pad "2" smd custom
			(at 0 0.4445 90)
			(size 0.1524 0.1524)
			(layers "F.Cu" "F.Mask" "F.Paste")
			(net "GND")
			(options
				(clearance outline)
				(anchor circle)
			)
			(primitives
				(gr_poly
					(pts
						(arc
							(start 0.3048 -0.2032)
							(mid 0.275042 -0.275042)
							(end 0.2032 -0.3048)
						)
						(arc
							(start -0.2032 -0.3048)
							(mid -0.275042 -0.275042)
							(end -0.3048 -0.2032)
						)
						(arc
							(start -0.3048 0.2032)
							(mid -0.275042 0.275042)
							(end -0.2032 0.3048)
						)
						(arc
							(start 0.2032 0.3048)
							(mid 0.275042 0.275042)
							(end 0.3048 0.2032)
						)
					)
					(width 0)
					(fill yes)
				)
			)
		)
	)
	(footprint ""
		(layer "F.Cu")
		(at 150.495 -160.401 180)
		(property "Reference" "C243"
			(at 0 0 180)
			(layer "F.SilkS")
			(hide yes)
			(effects
				(font
					(size 1.27 1.27)
				)
			)
		)
		(property "Value" "SC1U25V3KX-GP"
			(at 0 -2.8194 180)
			(unlocked yes)
			(layer "F.Fab")
			(hide yes)
			(effects
				(font
					(size 1.016 1.016)
					(thickness 0.1524)
				)
			)
		)
		(property "Device Type" "C603H36"
			(at 0 -4.3434 180)
			(unlocked yes)
			(layer "F.Fab")
			(hide yes)
			(effects
				(font
					(size 1.016 1.016)
					(thickness 0.1524)
				)
			)
		)
		(duplicate_pad_numbers_are_jumpers no)
		(fp_line
			(start 0.508 0)
			(end -0.508 0)
			(stroke
				(width 0.2032)
				(type default)
			)
			(layer "F.SilkS")
		)
		(fp_rect
			(start -0.5842 1.3335)
			(end 0.5842 -1.3335)
			(stroke
				(width 0)
				(type default)
			)
			(fill no)
			(layer "F.CrtYd")
		)
		(fp_rect
			(start -0.5842 1.3335)
			(end 0.5842 -1.3335)
			(stroke
				(width 0)
				(type default)
			)
			(fill no)
			(layer "F.Fab")
		)
		(pad "1" smd custom
			(at 0 -0.762 180)
			(size 0.2159 0.2159)
			(layers "F.Cu" "F.Mask" "F.Paste")
			(net "P12V_HDD16")
			(options
				(clearance outline)
				(anchor circle)
			)
			(primitives
				(gr_poly
					(pts
						(arc
							(start -0.3302 -0.4318)
							(mid -0.402042 -0.402042)
							(end -0.4318 -0.3302)
						)
						(arc
							(start -0.4318 0.3302)
							(mid -0.402042 0.402042)
							(end -0.3302 0.4318)
						)
						(arc
							(start 0.3302 0.4318)
							(mid 0.402042 0.402042)
							(end 0.4318 0.3302)
						)
						(arc
							(start 0.4318 -0.3302)
							(mid 0.402042 -0.402042)
							(end 0.3302 -0.4318)
						)
					)
					(width 0)
					(fill yes)
				)
			)
		)
		(pad "2" smd custom
			(at 0 0.762 180)
			(size 0.2159 0.2159)
			(layers "F.Cu" "F.Mask" "F.Paste")
			(net "GND")
			(options
				(clearance outline)
				(anchor circle)
			)
			(primitives
				(gr_poly
					(pts
						(arc
							(start -0.3302 -0.4318)
							(mid -0.402042 -0.402042)
							(end -0.4318 -0.3302)
						)
						(arc
							(start -0.4318 0.3302)
							(mid -0.402042 0.402042)
							(end -0.3302 0.4318)
						)
						(arc
							(start 0.3302 0.4318)
							(mid 0.402042 0.402042)
							(end 0.4318 0.3302)
						)
						(arc
							(start 0.4318 -0.3302)
							(mid 0.402042 -0.402042)
							(end 0.3302 -0.4318)
						)
					)
					(width 0)
					(fill yes)
				)
			)
		)
	)
	(footprint ""
		(layer "F.Cu")
		(at 54.0766 -131.2164 -90)
		(property "Reference" "R379"
			(at 0 0 270)
			(layer "F.SilkS")
			(hide yes)
			(effects
				(font
					(size 1.27 1.27)
				)
			)
		)
		(property "Value" "0R2J-2-GP"
			(at 0.064008 -3.993896 270)
			(unlocked yes)
			(layer "F.Fab")
			(hide yes)
			(effects
				(font
					(size 1.016 1.016)
					(thickness 0.1524)
				)
			)
		)
		(property "Device Type" "R402H16"
			(at 0.064008 -5.517896 270)
			(unlocked yes)
			(layer "F.Fab")
			(hide yes)
			(effects
				(font
					(size 1.016 1.016)
					(thickness 0.1524)
				)
			)
		)
		(duplicate_pad_numbers_are_jumpers no)
		(fp_line
			(start -0.508 -0.9398)
			(end -0.508 0.9398)
			(stroke
				(width 0.1524)
				(type default)
			)
			(layer "F.SilkS")
		)
		(fp_line
			(start 0.508 -0.9398)
			(end -0.508 -0.9398)
			(stroke
				(width 0.1524)
				(type default)
			)
			(layer "F.SilkS")
		)
		(fp_rect
			(start -0.508 0.9398)
			(end 0.508 -0.9398)
			(stroke
				(width 0)
				(type default)
			)
			(fill no)
			(layer "F.CrtYd")
		)
		(fp_rect
			(start -0.508 0.9398)
			(end 0.508 -0.9398)
			(stroke
				(width 0)
				(type default)
			)
			(fill no)
			(layer "F.Fab")
		)
		(pad "1" smd custom
			(at 0 -0.4445 270)
			(size 0.1397 0.1397)
			(layers "F.Cu" "F.Mask" "F.Paste")
			(net "DRIVE_B_13_PWR")
			(options
				(clearance outline)
				(anchor circle)
			)
			(primitives
				(gr_poly
					(pts
						(arc
							(start -0.1778 -0.2794)
							(mid -0.249642 -0.249642)
							(end -0.2794 -0.1778)
						)
						(arc
							(start -0.2794 0.1778)
							(mid -0.249642 0.249642)
							(end -0.1778 0.2794)
						)
						(arc
							(start 0.1778 0.2794)
							(mid 0.249642 0.249642)
							(end 0.2794 0.1778)
						)
						(arc
							(start 0.2794 -0.1778)
							(mid 0.249642 -0.249642)
							(end 0.1778 -0.2794)
						)
					)
					(width 0)
					(fill yes)
				)
			)
		)
		(pad "2" smd custom
			(at 0 0.4445 270)
			(size 0.1397 0.1397)
			(layers "F.Cu" "F.Mask" "F.Paste")
			(net "SW_PWR_R_HDD13")
			(options
				(clearance outline)
				(anchor circle)
			)
			(primitives
				(gr_poly
					(pts
						(arc
							(start -0.1778 -0.2794)
							(mid -0.249642 -0.249642)
							(end -0.2794 -0.1778)
						)
						(arc
							(start -0.2794 0.1778)
							(mid -0.249642 0.249642)
							(end -0.1778 0.2794)
						)
						(arc
							(start 0.1778 0.2794)
							(mid 0.249642 0.249642)
							(end 0.2794 0.1778)
						)
						(arc
							(start 0.2794 -0.1778)
							(mid 0.249642 -0.249642)
							(end 0.1778 -0.2794)
						)
					)
					(width 0)
					(fill yes)
				)
			)
		)
	)
	(footprint ""
		(layer "F.Cu")
		(at 86.106 -249.555 90)
		(property "Reference" "R199"
			(at 0 0 90)
			(layer "F.SilkS")
			(hide yes)
			(effects
				(font
					(size 1.27 1.27)
				)
			)
		)
		(property "Value" "4K7R2F-GP"
			(at 0.064008 -3.993896 90)
			(unlocked yes)
			(layer "F.Fab")
			(hide yes)
			(effects
				(font
					(size 1.016 1.016)
					(thickness 0.1524)
				)
			)
		)
		(property "Device Type" "R402H16"
			(at 0.064008 -5.517896 90)
			(unlocked yes)
			(layer "F.Fab")
			(hide yes)
			(effects
				(font
					(size 1.016 1.016)
					(thickness 0.1524)
				)
			)
		)
		(duplicate_pad_numbers_are_jumpers no)
		(fp_line
			(start 0.508 -0.9398)
			(end -0.508 -0.9398)
			(stroke
				(width 0.1524)
				(type default)
			)
			(layer "F.SilkS")
		)
		(fp_line
			(start -0.508 -0.9398)
			(end -0.508 0.9398)
			(stroke
				(width 0.1524)
				(type default)
			)
			(layer "F.SilkS")
		)
		(fp_rect
			(start -0.508 0.9398)
			(end 0.508 -0.9398)
			(stroke
				(width 0)
				(type default)
			)
			(fill no)
			(layer "F.CrtYd")
		)
		(fp_rect
			(start -0.508 0.9398)
			(end 0.508 -0.9398)
			(stroke
				(width 0)
				(type default)
			)
			(fill no)
			(layer "F.Fab")
		)
		(pad "1" smd custom
			(at 0 -0.4445 90)
			(size 0.1397 0.1397)
			(layers "F.Cu" "F.Mask" "F.Paste")
			(net "SW_PWR_R_HDD2")
			(options
				(clearance outline)
				(anchor circle)
			)
			(primitives
				(gr_poly
					(pts
						(arc
							(start -0.1778 -0.2794)
							(mid -0.249642 -0.249642)
							(end -0.2794 -0.1778)
						)
						(arc
							(start -0.2794 0.1778)
							(mid -0.249642 0.249642)
							(end -0.1778 0.2794)
						)
						(arc
							(start 0.1778 0.2794)
							(mid 0.249642 0.249642)
							(end 0.2794 0.1778)
						)
						(arc
							(start 0.2794 -0.1778)
							(mid 0.249642 -0.249642)
							(end 0.1778 -0.2794)
						)
					)
					(width 0)
					(fill yes)
				)
			)
		)
		(pad "2" smd custom
			(at 0 0.4445 90)
			(size 0.1397 0.1397)
			(layers "F.Cu" "F.Mask" "F.Paste")
			(net "GND")
			(options
				(clearance outline)
				(anchor circle)
			)
			(primitives
				(gr_poly
					(pts
						(arc
							(start -0.1778 -0.2794)
							(mid -0.249642 -0.249642)
							(end -0.2794 -0.1778)
						)
						(arc
							(start -0.2794 0.1778)
							(mid -0.249642 0.249642)
							(end -0.1778 0.2794)
						)
						(arc
							(start 0.1778 0.2794)
							(mid 0.249642 0.249642)
							(end 0.2794 0.1778)
						)
						(arc
							(start 0.2794 -0.1778)
							(mid 0.249642 -0.249642)
							(end 0.1778 -0.2794)
						)
					)
					(width 0)
					(fill yes)
				)
			)
		)
	)
	(footprint ""
		(layer "F.Cu")
		(at 301.979076 -340.812882 180)
		(property "Reference" "R95"
			(at 0 0 180)
			(layer "F.SilkS")
			(hide yes)
			(effects
				(font
					(size 1.27 1.27)
				)
			)
		)
		(property "Value" "0R2J-2-GP"
			(at 0.064008 -3.993896 180)
			(unlocked yes)
			(layer "F.Fab")
			(hide yes)
			(effects
				(font
					(size 1.016 1.016)
					(thickness 0.1524)
				)
			)
		)
		(property "Device Type" "R402H16"
			(at 0.064008 -5.517896 180)
			(unlocked yes)
			(layer "F.Fab")
			(hide yes)
			(effects
				(font
					(size 1.016 1.016)
					(thickness 0.1524)
				)
			)
		)
		(duplicate_pad_numbers_are_jumpers no)
		(fp_line
			(start 0.508 -0.9398)
			(end -0.508 -0.9398)
			(stroke
				(width 0.1524)
				(type default)
			)
			(layer "F.SilkS")
		)
		(fp_line
			(start -0.508 -0.9398)
			(end -0.508 0.9398)
			(stroke
				(width 0.1524)
				(type default)
			)
			(layer "F.SilkS")
		)
		(fp_rect
			(start -0.508 0.9398)
			(end 0.508 -0.9398)
			(stroke
				(width 0)
				(type default)
			)
			(fill no)
			(layer "F.CrtYd")
		)
		(fp_rect
			(start -0.508 0.9398)
			(end 0.508 -0.9398)
			(stroke
				(width 0)
				(type default)
			)
			(fill no)
			(layer "F.Fab")
		)
		(pad "1" smd custom
			(at 0 -0.4445 180)
			(size 0.1397 0.1397)
			(layers "F.Cu" "F.Mask" "F.Paste")
			(net "PWM_OUT_C_R")
			(options
				(clearance outline)
				(anchor circle)
			)
			(primitives
				(gr_poly
					(pts
						(arc
							(start -0.1778 -0.2794)
							(mid -0.249642 -0.249642)
							(end -0.2794 -0.1778)
						)
						(arc
							(start -0.2794 0.1778)
							(mid -0.249642 0.249642)
							(end -0.1778 0.2794)
						)
						(arc
							(start 0.1778 0.2794)
							(mid 0.249642 0.249642)
							(end 0.2794 0.1778)
						)
						(arc
							(start 0.2794 -0.1778)
							(mid 0.249642 -0.249642)
							(end 0.1778 -0.2794)
						)
					)
					(width 0)
					(fill yes)
				)
			)
		)
		(pad "2" smd custom
			(at 0 0.4445 180)
			(size 0.1397 0.1397)
			(layers "F.Cu" "F.Mask" "F.Paste")
			(net "PWM_OUT_C")
			(options
				(clearance outline)
				(anchor circle)
			)
			(primitives
				(gr_poly
					(pts
						(arc
							(start -0.1778 -0.2794)
							(mid -0.249642 -0.249642)
							(end -0.2794 -0.1778)
						)
						(arc
							(start -0.2794 0.1778)
							(mid -0.249642 0.249642)
							(end -0.1778 0.2794)
						)
						(arc
							(start 0.1778 0.2794)
							(mid 0.249642 0.249642)
							(end 0.2794 0.1778)
						)
						(arc
							(start 0.2794 -0.1778)
							(mid 0.249642 -0.249642)
							(end 0.1778 -0.2794)
						)
					)
					(width 0)
					(fill yes)
				)
			)
		)
	)
	(footprint ""
		(layer "F.Cu")
		(at 250.782582 -133.291072)
		(property "Reference" "R424"
			(at 0 0 0)
			(layer "F.SilkS")
			(hide yes)
			(effects
				(font
					(size 1.27 1.27)
				)
			)
		)
		(property "Value" "0R2J-2-GP"
			(at 0.064008 -3.993896 0)
			(unlocked yes)
			(layer "F.Fab")
			(hide yes)
			(effects
				(font
					(size 1.016 1.016)
					(thickness 0.1524)
				)
			)
		)
		(property "Device Type" "R402H16"
			(at 0.064008 -5.517896 0)
			(unlocked yes)
			(layer "F.Fab")
			(hide yes)
			(effects
				(font
					(size 1.016 1.016)
					(thickness 0.1524)
				)
			)
		)
		(duplicate_pad_numbers_are_jumpers no)
		(fp_line
			(start -0.508 -0.9398)
			(end -0.508 0.9398)
			(stroke
				(width 0.1524)
				(type default)
			)
			(layer "F.SilkS")
		)
		(fp_line
			(start 0.508 -0.9398)
			(end -0.508 -0.9398)
			(stroke
				(width 0.1524)
				(type default)
			)
			(layer "F.SilkS")
		)
		(fp_rect
			(start -0.508 0.9398)
			(end 0.508 -0.9398)
			(stroke
				(width 0)
				(type default)
			)
			(fill no)
			(layer "F.CrtYd")
		)
		(fp_rect
			(start -0.508 0.9398)
			(end 0.508 -0.9398)
			(stroke
				(width 0)
				(type default)
			)
			(fill no)
			(layer "F.Fab")
		)
		(pad "1" smd custom
			(at 0 -0.4445)
			(size 0.1397 0.1397)
			(layers "F.Cu" "F.Mask" "F.Paste")
			(net "I2C_DPB_B_SDA_BUF")
			(options
				(clearance outline)
				(anchor circle)
			)
			(primitives
				(gr_poly
					(pts
						(arc
							(start -0.1778 -0.2794)
							(mid -0.249642 -0.249642)
							(end -0.2794 -0.1778)
						)
						(arc
							(start -0.2794 0.1778)
							(mid -0.249642 0.249642)
							(end -0.1778 0.2794)
						)
						(arc
							(start 0.1778 0.2794)
							(mid 0.249642 0.249642)
							(end 0.2794 0.1778)
						)
						(arc
							(start 0.2794 -0.1778)
							(mid 0.249642 -0.249642)
							(end 0.1778 -0.2794)
						)
					)
					(width 0)
					(fill yes)
				)
			)
		)
		(pad "2" smd custom
			(at 0 0.4445)
			(size 0.1397 0.1397)
			(layers "F.Cu" "F.Mask" "F.Paste")
			(net "I2C_DPB_B_SDA")
			(options
				(clearance outline)
				(anchor circle)
			)
			(primitives
				(gr_poly
					(pts
						(arc
							(start -0.1778 -0.2794)
							(mid -0.249642 -0.249642)
							(end -0.2794 -0.1778)
						)
						(arc
							(start -0.2794 0.1778)
							(mid -0.249642 0.249642)
							(end -0.1778 0.2794)
						)
						(arc
							(start 0.1778 0.2794)
							(mid 0.249642 0.249642)
							(end 0.2794 0.1778)
						)
						(arc
							(start 0.2794 -0.1778)
							(mid 0.249642 -0.249642)
							(end 0.1778 -0.2794)
						)
					)
					(width 0)
					(fill yes)
				)
			)
		)
	)
	(footprint ""
		(layer "F.Cu")
		(at 239.776 -215.265)
		(property "Reference" "R84"
			(at 0 0 0)
			(layer "F.SilkS")
			(hide yes)
			(effects
				(font
					(size 1.27 1.27)
				)
			)
		)
		(property "Value" "4K7R2F-GP"
			(at 0.064008 -3.993896 0)
			(unlocked yes)
			(layer "F.Fab")
			(hide yes)
			(effects
				(font
					(size 1.016 1.016)
					(thickness 0.1524)
				)
			)
		)
		(property "Device Type" "R402H16"
			(at 0.064008 -5.517896 0)
			(unlocked yes)
			(layer "F.Fab")
			(hide yes)
			(effects
				(font
					(size 1.016 1.016)
					(thickness 0.1524)
				)
			)
		)
		(duplicate_pad_numbers_are_jumpers no)
		(fp_line
			(start -0.508 -0.9398)
			(end -0.508 0.9398)
			(stroke
				(width 0.1524)
				(type default)
			)
			(layer "F.SilkS")
		)
		(fp_line
			(start 0.508 -0.9398)
			(end -0.508 -0.9398)
			(stroke
				(width 0.1524)
				(type default)
			)
			(layer "F.SilkS")
		)
		(fp_rect
			(start -0.508 0.9398)
			(end 0.508 -0.9398)
			(stroke
				(width 0)
				(type default)
			)
			(fill no)
			(layer "F.CrtYd")
		)
		(fp_rect
			(start -0.508 0.9398)
			(end 0.508 -0.9398)
			(stroke
				(width 0)
				(type default)
			)
			(fill no)
			(layer "F.Fab")
		)
		(pad "1" smd custom
			(at 0 -0.4445)
			(size 0.1397 0.1397)
			(layers "F.Cu" "F.Mask" "F.Paste")
			(net "IO_EXP3_A0")
			(options
				(clearance outline)
				(anchor circle)
			)
			(primitives
				(gr_poly
					(pts
						(arc
							(start -0.1778 -0.2794)
							(mid -0.249642 -0.249642)
							(end -0.2794 -0.1778)
						)
						(arc
							(start -0.2794 0.1778)
							(mid -0.249642 0.249642)
							(end -0.1778 0.2794)
						)
						(arc
							(start 0.1778 0.2794)
							(mid 0.249642 0.249642)
							(end 0.2794 0.1778)
						)
						(arc
							(start 0.2794 -0.1778)
							(mid 0.249642 -0.249642)
							(end 0.1778 -0.2794)
						)
					)
					(width 0)
					(fill yes)
				)
			)
		)
		(pad "2" smd custom
			(at 0 0.4445)
			(size 0.1397 0.1397)
			(layers "F.Cu" "F.Mask" "F.Paste")
			(net "GND")
			(options
				(clearance outline)
				(anchor circle)
			)
			(primitives
				(gr_poly
					(pts
						(arc
							(start -0.1778 -0.2794)
							(mid -0.249642 -0.249642)
							(end -0.2794 -0.1778)
						)
						(arc
							(start -0.2794 0.1778)
							(mid -0.249642 0.249642)
							(end -0.1778 0.2794)
						)
						(arc
							(start 0.1778 0.2794)
							(mid 0.249642 0.249642)
							(end 0.2794 0.1778)
						)
						(arc
							(start 0.2794 -0.1778)
							(mid 0.249642 -0.249642)
							(end 0.1778 -0.2794)
						)
					)
					(width 0)
					(fill yes)
				)
			)
		)
	)
)
